# T6G (Grand Teton) — schematic netlist excerpt (pin names and nets, part order shuffled) for the footprints in the layout excerpt that follows; sources: Cadence DE-HDL packaged netlist, KiCad conversion of 04192023_DAF0TMB3IC0_F0TG_MB_C_brd_V02_OCP.brd

J59  SCONN75K_APCI0155P004A  SCONN75K_APCI0155-P004A EMPTY  pkg CON_F67S2H2D2S_P0-5W7-55_LUVXB_H270  page 144
  GND1  = PCIE_M2_SSD0_PRSNT_N
  \3.3v_1\  = P3V3_M2_0
  GND2  = GND
  \3.3v_2\  = P3V3_M2_0
  PERN3  = P3E_CPU1_P4_RX_DN<3>
  NC1  = NC_M2_0_NC1
  PERP3  = P3E_CPU1_P4_RX_DP<3>
  NC2  = NC_M2_0_NC2
  GND3  = GND
  \das_dss#||led1#\  = LED_M2_SSD_0_ACT_N
  PETN3  = P3E_CPU1_P4_TX_C_DN<3>
  \3.3v_3\  = P3V3_M2_0
  PETP3  = P3E_CPU1_P4_TX_C_DP<3>
  \3.3v_4\  = P3V3_M2_0
  GND4  = GND
  \3.3v_5\  = P3V3_M2_0
  PERN2  = P3E_CPU1_P4_RX_DN<2>
  \3.3v_6\  = P3V3_M2_0
  PERP2  = P3E_CPU1_P4_RX_DP<2>
  NC3  = NC_M2_0_NC3
  GND5  = GND
  NC4  = NC_M2_0_NC4
  PETN2  = P3E_CPU1_P4_TX_C_DN<2>
  NC5  = NC_M2_0_NC5
  PETP2  = P3E_CPU1_P4_TX_C_DP<2>
  NC6  = NC_M2_0_NC6
  GND6  = GND
  NC7  = NC_M2_0_NC7
  PERN1  = P3E_CPU1_P4_RX_DN<1>
  NC8  = NC_M2_0_NC8
  PERP1  = P3E_CPU1_P4_RX_DP<1>
  NC9  = NC_M2_0_NC9
  GND7  = GND
  NC10  = NC_M2_0_NC10
  PETN1  = P3E_CPU1_P4_TX_C_DN<1>
  NC11  = NC_M2_0_NC11
  PETP1  = P3E_CPU1_P4_TX_C_DP<1>
  DEVSLP  = PD_M2_0_DEVSLP
  GND8  = GND
  NC12  = SMB_M2_P1_1V8AUX_SCL
  \pern0||sata-b+\  = P3E_CPU1_P4_RX_DN<0>
  NC13  = SMB_M2_P1_1V8AUX_SDA
  \perp0||sata-b-\  = P3E_CPU1_P4_RX_DP<0>
  NC14  = NC_M2_0_NC14
  GND9  = GND
  NC15  = NC_M2_0_NC15
  \petn0||sata-a-\  = P3E_CPU1_P4_TX_C_DN<0>
  NC16  = NC_M2_0_NC16
  \petp0||sata-a+\  = P3E_CPU1_P4_TX_C_DP<0>
  \perst#\  = RST_PERST_BUF_M2_0_R_N
  GND10  = GND
  \clkreq#\  = M2_SSD0_CLKREQ_EN_N_BUF
  REFCLKN  = CLK_100M_CPU1_CLK12_DN
  \pewake#\  = M2_0_PEWAKE_N
  REFCLKP  = CLK_100M_CPU1_CLK12_DP
  NC17  = NC_M2_0_NC17
  GND11  = GND
  NC18  = NC_M2_0_NC18
  NC19  = NC_M2_0_NC19
  SUSCLK  = NC_M2_0_SUSCLK
  PEDET  = FM_M2_SSD_0_PEDET
  \3.3v_7\  = P3V3_M2_0
  GND12  = GND
  \3.3v_8\  = P3V3_M2_0
  GND13  = GND
  \3.3v_9\  = P3V3_M2_0
  GND14  = GND
  G1  = GND
  G2  = GND

(kicad_pcb
	(version 20260206)
	(generator "pcbnew")
	(generator_version "10.0")
	(general
		(thickness 1.6)
		(legacy_teardrops no)
	)
	(paper "A4")
	(title_block
		(title "04192023_DAF0TMB3IC0_F0TG_MB_C_brd_V02_OCP.brd")
		(comment 1 "Grand Teton / footprint 1180 of 8354 (J59), pads 1-44 of 71")
	)
	(layers
		(0 "F.Cu" signal "TOP")
		(4 "In1.Cu" signal "GND")
		(6 "In2.Cu" signal "IN1")
		(8 "In3.Cu" signal "GND1")
		(10 "In4.Cu" signal "IN2")
		(12 "In5.Cu" signal "GND2")
		(14 "In6.Cu" signal "IN3")
		(16 "In7.Cu" signal "GND3")
		(18 "In8.Cu" signal "VCC")
		(20 "In9.Cu" signal "VCC1")
		(22 "In10.Cu" signal "GND4")
		(24 "In11.Cu" signal "IN4")
		(26 "In12.Cu" signal "GND5")
		(28 "In13.Cu" signal "IN5")
		(30 "In14.Cu" signal "GND6")
		(32 "In15.Cu" signal "IN6")
		(34 "In16.Cu" signal "GND7")
		(2 "B.Cu" signal "BOTTOM")
		(9 "F.Adhes" user "F.Adhesive")
		(11 "B.Adhes" user "B.Adhesive")
		(13 "F.Paste" user "Package Geometry/Pastemask Top")
		(15 "B.Paste" user "Package Geometry/Pastemask Bottom")
		(5 "F.SilkS" user "Ref Des/Silkscreen Top")
		(7 "B.SilkS" user "Ref Des/Silkscreen Bottom")
		(1 "F.Mask" user "Board Geometry/Soldermask Top")
		(3 "B.Mask" user "Board Geometry/Soldermask Bottom")
		(17 "Dwgs.User" user "User.Drawings")
		(19 "Cmts.User" user "User.Comments")
		(21 "Eco1.User" user "User.Eco1")
		(23 "Eco2.User" user "User.Eco2")
		(25 "Edge.Cuts" user "Board Geometry/Outline")
		(27 "Margin" user)
		(31 "F.CrtYd" user "Package Geometry/Place Bound Top")
		(29 "B.CrtYd" user "Package Geometry/Place Bound Bottom")
		(35 "F.Fab" user "Ref Des/Assembly Top")
		(33 "B.Fab" user "Ref Des/Assembly Bottom")
	)
	(footprint ""
		(layer "F.Cu")
		(at 173.358302 -47.049944)
		(property "Reference" "J59"
			(at -4.4958 -11.852148 0)
			(unlocked yes)
			(layer "F.SilkS")
			(effects
				(font
					(size 0.7874 0.5842)
					(thickness 0.1524)
				)
				(justify left)
			)
		)
		(property "Value" ""
			(at 0 0 0)
			(layer "F.Fab")
			(effects
				(font
					(size 1.27 1.27)
				)
			)
		)
		(duplicate_pad_numbers_are_jumpers no)
		(pad "" np_thru_hole circle
			(at -1.525016 -9.99998 270)
			(size 1.1684 1.1684)
			(drill 1.1684)
			(layers "*.Cu" "*.Mask")
			(clearance 0.381)
			(thermal_gap 0.381)
		)
		(pad "" np_thru_hole circle
			(at -1.525016 9.99998 270)
			(size 1.651 1.651)
			(drill 1.651)
			(layers "*.Cu" "*.Mask")
			(clearance 0.381)
			(thermal_gap 0.381)
		)
		(pad "1" smd rect
			(at 3.750056 -9.249918 270)
			(size 0.2794 1.6002)
			(layers "F.Cu" "F.Mask" "F.Paste")
			(net "PCIE_M2_SSD0_PRSNT_N")
		)
		(pad "2" smd rect
			(at -3.800094 -8.999982 270)
			(size 0.2794 1.6002)
			(layers "F.Cu" "F.Mask" "F.Paste")
			(net "P3V3_M2_0")
		)
		(pad "3" smd rect
			(at 3.750056 -8.750046 270)
			(size 0.2794 1.6002)
			(layers "F.Cu" "F.Mask" "F.Paste")
			(net "GND")
		)
		(pad "4" smd rect
			(at -3.800094 -8.50011 270)
			(size 0.2794 1.6002)
			(layers "F.Cu" "F.Mask" "F.Paste")
			(net "P3V3_M2_0")
		)
		(pad "5" smd rect
			(at 3.750056 -8.24992 270)
			(size 0.2794 1.6002)
			(layers "F.Cu" "F.Mask" "F.Paste")
			(net "P3E_CPU1_P4_RX_DN<3>")
		)
		(pad "6" smd rect
			(at -3.800094 -7.999984 270)
			(size 0.2794 1.6002)
			(layers "F.Cu" "F.Mask" "F.Paste")
			(net "NC_M2_0_NC1")
		)
		(pad "7" smd rect
			(at 3.750056 -7.750048 270)
			(size 0.2794 1.6002)
			(layers "F.Cu" "F.Mask" "F.Paste")
			(net "P3E_CPU1_P4_RX_DP<3>")
		)
		(pad "8" smd rect
			(at -3.800094 -7.500112 270)
			(size 0.2794 1.6002)
			(layers "F.Cu" "F.Mask" "F.Paste")
			(net "NC_M2_0_NC2")
		)
		(pad "9" smd rect
			(at 3.750056 -7.249922 270)
			(size 0.2794 1.6002)
			(layers "F.Cu" "F.Mask" "F.Paste")
			(net "GND")
		)
		(pad "10" smd rect
			(at -3.800094 -6.999986 270)
			(size 0.2794 1.6002)
			(layers "F.Cu" "F.Mask" "F.Paste")
			(net "LED_M2_SSD_0_ACT_N")
		)
		(pad "11" smd rect
			(at 3.750056 -6.75005 270)
			(size 0.2794 1.6002)
			(layers "F.Cu" "F.Mask" "F.Paste")
			(net "P3E_CPU1_P4_TX_C_DN<3>")
		)
		(pad "12" smd rect
			(at -3.800094 -6.500114 270)
			(size 0.2794 1.6002)
			(layers "F.Cu" "F.Mask" "F.Paste")
			(net "P3V3_M2_0")
		)
		(pad "13" smd rect
			(at 3.750056 -6.249924 270)
			(size 0.2794 1.6002)
			(layers "F.Cu" "F.Mask" "F.Paste")
			(net "P3E_CPU1_P4_TX_C_DP<3>")
		)
		(pad "14" smd rect
			(at -3.800094 -5.999988 270)
			(size 0.2794 1.6002)
			(layers "F.Cu" "F.Mask" "F.Paste")
			(net "P3V3_M2_0")
		)
		(pad "15" smd rect
			(at 3.750056 -5.750052 270)
			(size 0.2794 1.6002)
			(layers "F.Cu" "F.Mask" "F.Paste")
			(net "GND")
		)
		(pad "16" smd rect
			(at -3.800094 -5.500116 270)
			(size 0.2794 1.6002)
			(layers "F.Cu" "F.Mask" "F.Paste")
			(net "P3V3_M2_0")
		)
		(pad "17" smd rect
			(at 3.750056 -5.249926 270)
			(size 0.2794 1.6002)
			(layers "F.Cu" "F.Mask" "F.Paste")
			(net "P3E_CPU1_P4_RX_DN<2>")
		)
		(pad "18" smd rect
			(at -3.800094 -4.99999 270)
			(size 0.2794 1.6002)
			(layers "F.Cu" "F.Mask" "F.Paste")
			(net "P3V3_M2_0")
		)
		(pad "19" smd rect
			(at 3.750056 -4.750054 270)
			(size 0.2794 1.6002)
			(layers "F.Cu" "F.Mask" "F.Paste")
			(net "P3E_CPU1_P4_RX_DP<2>")
		)
		(pad "20" smd rect
			(at -3.800094 -4.500118 270)
			(size 0.2794 1.6002)
			(layers "F.Cu" "F.Mask" "F.Paste")
			(net "NC_M2_0_NC3")
		)
		(pad "21" smd rect
			(at 3.750056 -4.249928 270)
			(size 0.2794 1.6002)
			(layers "F.Cu" "F.Mask" "F.Paste")
			(net "GND")
		)
		(pad "22" smd rect
			(at -3.800094 -3.999992 270)
			(size 0.2794 1.6002)
			(layers "F.Cu" "F.Mask" "F.Paste")
			(net "NC_M2_0_NC4")
		)
		(pad "23" smd rect
			(at 3.750056 -3.750056 270)
			(size 0.2794 1.6002)
			(layers "F.Cu" "F.Mask" "F.Paste")
			(net "P3E_CPU1_P4_TX_C_DN<2>")
		)
		(pad "24" smd rect
			(at -3.800094 -3.50012 270)
			(size 0.2794 1.6002)
			(layers "F.Cu" "F.Mask" "F.Paste")
			(net "NC_M2_0_NC5")
		)
		(pad "25" smd rect
			(at 3.750056 -3.24993 270)
			(size 0.2794 1.6002)
			(layers "F.Cu" "F.Mask" "F.Paste")
			(net "P3E_CPU1_P4_TX_C_DP<2>")
		)
		(pad "26" smd rect
			(at -3.800094 -2.999994 270)
			(size 0.2794 1.6002)
			(layers "F.Cu" "F.Mask" "F.Paste")
			(net "NC_M2_0_NC6")
		)
		(pad "27" smd rect
			(at 3.750056 -2.750058 270)
			(size 0.2794 1.6002)
			(layers "F.Cu" "F.Mask" "F.Paste")
			(net "GND")
		)
		(pad "28" smd rect
			(at -3.800094 -2.500122 270)
			(size 0.2794 1.6002)
			(layers "F.Cu" "F.Mask" "F.Paste")
			(net "NC_M2_0_NC7")
		)
		(pad "29" smd rect
			(at 3.750056 -2.249932 270)
			(size 0.2794 1.6002)
			(layers "F.Cu" "F.Mask" "F.Paste")
			(net "P3E_CPU1_P4_RX_DN<1>")
		)
		(pad "30" smd rect
			(at -3.800094 -1.999996 270)
			(size 0.2794 1.6002)
			(layers "F.Cu" "F.Mask" "F.Paste")
			(net "NC_M2_0_NC8")
		)
		(pad "31" smd rect
			(at 3.750056 -1.75006 270)
			(size 0.2794 1.6002)
			(layers "F.Cu" "F.Mask" "F.Paste")
			(net "P3E_CPU1_P4_RX_DP<1>")
		)
		(pad "32" smd rect
			(at -3.800094 -1.500124 270)
			(size 0.2794 1.6002)
			(layers "F.Cu" "F.Mask" "F.Paste")
			(net "NC_M2_0_NC9")
		)
		(pad "33" smd rect
			(at 3.750056 -1.249934 270)
			(size 0.2794 1.6002)
			(layers "F.Cu" "F.Mask" "F.Paste")
			(net "GND")
		)
		(pad "34" smd rect
			(at -3.800094 -0.999998 270)
			(size 0.2794 1.6002)
			(layers "F.Cu" "F.Mask" "F.Paste")
			(net "NC_M2_0_NC10")
		)
		(pad "35" smd rect
			(at 3.750056 -0.750062 270)
			(size 0.2794 1.6002)
			(layers "F.Cu" "F.Mask" "F.Paste")
			(net "P3E_CPU1_P4_TX_C_DN<1>")
		)
		(pad "36" smd rect
			(at -3.800094 -0.499872 270)
			(size 0.2794 1.6002)
			(layers "F.Cu" "F.Mask" "F.Paste")
			(net "NC_M2_0_NC11")
		)
		(pad "37" smd rect
			(at 3.750056 -0.249936 270)
			(size 0.2794 1.6002)
			(layers "F.Cu" "F.Mask" "F.Paste")
			(net "P3E_CPU1_P4_TX_C_DP<1>")
		)
		(pad "38" smd rect
			(at -3.800094 0 270)
			(size 0.2794 1.6002)
			(layers "F.Cu" "F.Mask" "F.Paste")
			(net "PD_M2_0_DEVSLP")
		)
		(pad "39" smd rect
			(at 3.750056 0.249936 270)
			(size 0.2794 1.6002)
			(layers "F.Cu" "F.Mask" "F.Paste")
			(net "GND")
		)
		(pad "40" smd rect
			(at -3.800094 0.499872 270)
			(size 0.2794 1.6002)
			(layers "F.Cu" "F.Mask" "F.Paste")
			(net "SMB_M2_P1_1V8AUX_SCL")
		)
		(pad "41" smd rect
			(at 3.750056 0.750062 270)
			(size 0.2794 1.6002)
			(layers "F.Cu" "F.Mask" "F.Paste")
			(net "P3E_CPU1_P4_RX_DN<0>")
		)
		(pad "42" smd rect
			(at -3.800094 0.999998 270)
			(size 0.2794 1.6002)
			(layers "F.Cu" "F.Mask" "F.Paste")
			(net "SMB_M2_P1_1V8AUX_SDA")
		)
	)
)
